FILE_TYPE = CONNECTIVITY;
{Allegro Design Entry HDL 17.2-2016 S081 (4005846) 1/11/2022}
"PAGE_NUMBER" = 195;
0"NC";
1"GND\g";
2"GND\g";
3"GND\g";
4"GND\g";
5"GND\g";
6"GND\g";
7"GND\g";
8"GND\g";
9"GND\g";
10"GND\g";
11"GND\g";
12"SW_PVDDCR_CPU1_P1_BOOT6_R";
13"GND\g";
14"SW_PVDDCR_CPU1_P1_SW6";
15"SW_PVDDCR_CPU1_P1_BOOTR6";
16"SW_PVDDCR_CPU1_P1_BOOTR5";
17"SW_PVDDCR_CPU1_P1_SW5";
18"GND\g";
19"GND\g";
20"IND_CPU1_P1_CPL6";
21"SW_PVDDCR_CPU1_P1_BOOT5_R";
22"GND\g";
23"SW_PVDDCR_CPU1_P1_SW5_RC";
24"IND_CPU1_P1_CPL6";
25"PVDDCR_CPU1_P1\g";
26"SW_PVDDCR_CPU1_P1_SW6_RC";
27"NC_PVDDCR_CPU1_P1_GL1_6";
28"NC_PVDDCR_CPU1_P1_GL2_6";
29"SW_PVDDCR_CPU1_P1_BOOT6";
30"SW_PVDDCR_CPU1_P1_BOOT5";
31"NC_PVDDCR_CPU1_P1_GL1_5";
32"NC_PVDDCR_CPU1_P1_GL2_5";
33"SW_P12V_STBY_PVDDCR_CPU1_P1_FLT\g";
34"NC_PVDDCR_CPU1_P1_DNC5";
35"PVDDCR_CPU1_P1_IMON5";
36"PVDDCR_CPU1_P1_VCCS"CDS_PHYS_NET_NAME"PVCCIN_CPU0_VREF";
37"PVDDCR_CPU1_P1_VCC5";
38"PVDDCR_CPU1_P1_LSET5";
39"PVDDCR_CPU1_P1_PVCC\g";
40"GND\g";
41"NC_PVDDCR_CPU1_P1_DNC6";
42"PVDDCR_CPU1_P1_TEMP0";
43"PVDDCR_CPU1_P1_PWM5";
44"PVDDCR_CPU1_P1_TEMP0";
45"PVDDCR_CPU1_P1_IMON6";
46"PVDDCR_CPU1_P1_VCCS"CDS_PHYS_NET_NAME"PVCCIN_CPU0_VREF";
47"PVDDCR_CPU1_P1_PVCC\g";
48"PVDDCR_CPU1_P1_VCC6";
49"SW_P12V_STBY_PVDDCR_CPU1_P1_FLT\g";
50"PVDDCR_CPU1_P1_VOS5";
51"IND_CPU1_P1_CPL5";
52"PVDDCR_CPU1_P1\g";
53"IND_CPU1_P1_CPL0";
54"PVDDCR_CPU1_P1_VOS6";
55"PVDDCR_CPU1_P1_LSET6";
56"GND\g";
57"PVDDCR_CPU1_P1_PWM6";
%"Q_INDUCTOR4P_14"
"1","(6850,1800)","0","pure_quanta","I100";
;
LOCATION"PL69"
$SEC"1"
CDS_SEC"1"
MATERIAL"IND"
PART_TYPE"SMLF"
VALUE"150NH"
PART_NUMBER"CV+15^0TZ04"
CDS_LIB"pure_quanta"
NEEDS_NO_SIZE"TRUE";
"1"
$PN"1"14;
"4"
$PN"4"25;
"3"
$PN"3"24;
"2"
$PN"2"53;
%"VCC_CORE"
"1","(5850,3175)","0","pure_quanta_power","I101";
;
HDL_POWER"SW_P12V_STBY_PVDDCR_CPU1_P1_FLT"
CDS_LIB"pure_quanta_power";
"A"49;
%"Q_CAP"
"1","(5850,2825)","0","pure_quanta","I102";
;
LOCATION"PC147_6"
$SEC"1"
CDS_SEC"1"
MATERIAL"X6S"
TOLERANCE"10%"
VALUE"10UF"
PART_NUMBER"CH6104KEA00"
VOLTAGE"25V"
PACK_TYPE"C0805"
CDS_LIB"pure_quanta";
"B"
$PN"2"13;
"A"
$PN"1"49;
%"Q_CAP"
"1","(5475,2825)","0","pure_quanta","I103";
;
LOCATION"PC145_6"
$SEC"1"
CDS_SEC"1"
MATERIAL"X6S"
TOLERANCE"10%"
VALUE"10UF"
VOLTAGE"25V"
PACK_TYPE"C0805"
PART_NUMBER"CH6104KEA00"
CDS_LIB"pure_quanta";
"B"
$PN"2"13;
"A"
$PN"1"49;
%"UNIVERSAL_GND"
"1","(5850,2475)","0","pure_quanta_power","I104";
;
CDS_LIB"pure_quanta_power"
HDL_POWER"GND";
"A"13;
%"Q_CAP"
"1","(5650,2150)","0","pure_quanta","I106";
;
LOCATION"PC146"
$SEC"1"
CDS_SEC"1"
MATERIAL"X7R"
TOLERANCE"10%"
VALUE"0.22UF"
PART_NUMBER"CH4223K1B00"
VOLTAGE"16V"
PACK_TYPE"0402"
CDS_LIB"pure_quanta";
"B"
$PN"2"15;
"A"
$PN"1"12;
%"Q_CAP"
"1","(5075,2825)","0","pure_quanta","I107";
;
LOCATION"PC144_6"
$SEC"1"
CDS_SEC"1"
MATERIAL"X6S"
TOLERANCE"10%"
VALUE"10UF"
PART_NUMBER"CH6104KEA00"
VOLTAGE"25V"
PACK_TYPE"C0805"
CDS_LIB"pure_quanta";
"B"
$PN"2"13;
"A"
$PN"1"49;
%"Q_CAP"
"1","(4675,2825)","0","pure_quanta","I108";
;
LOCATION"PC141_6"
$SEC"1"
CDS_SEC"1"
VALUE"1UF"
MATERIAL"X6S"
TOLERANCE"10%"
PART_NUMBER"CH5104KEB02"
VOLTAGE"25V"
PACK_TYPE"C0402"
CDS_LIB"pure_quanta";
"B"
$PN"2"13;
"A"
$PN"1"49;
%"Q_CAP"
"1","(4250,2825)","0","pure_quanta","I109";
;
LOCATION"PC140_6"
$SEC"1"
CDS_SEC"1"
VOLTAGE"25V"
MATERIAL"X7R"
TOLERANCE"10%"
VALUE"0.1UF"
PART_NUMBER"CH4104K1B00"
PACK_TYPE"0402"
CDS_LIB"pure_quanta";
"B"
$PN"2"13;
"A"
$PN"1"49;
%"Q_RES"
"1","(4750,2275)","0","pure_quanta","I110";
;
LOCATION"PR428"
$SEC"1"
CDS_SEC"1"
PACK_TYPE"0402LF"
TOLERANCE"1%"
MATERIAL"CHIP"
WATTAGE"1/16W"
VALUE"4.7"
PART_NUMBER"CS-4702FB19"
CDS_LIB"pure_quanta";
"B"
$PN"2"12;
"A"
$PN"1"29;
%"Q_RES"
"1","(5950,775)","0","pure_quanta","I111";
;
LOCATION"PR429"
$SEC"1"
CDS_SEC"1"
WATTAGE"1/16W"
MATERIAL"CHIP"
TOLERANCE"5%"
VALUE"0"
PART_NUMBER"CS00002JB38"
PACK_TYPE"0402LF"
CDS_LIB"pure_quanta";
"B"
$PN"2"25;
"A"
$PN"1"54;
%"Q_CAP"
"1","(2275,2925)","0","pure_quanta","I112";
;
LOCATION"PC139_C1P1_6"
$SEC"1"
CDS_SEC"1"
MATERIAL"X6S"
TOLERANCE"10%"
VALUE"2.2UF"
PART_NUMBER"CH5222KEB01"
VOLTAGE"10V"
PACK_TYPE"C0402"
CDS_LIB"pure_quanta";
"B"
$PN"2"1;
"A"
$PN"1"47;
%"UNIVERSAL_GND"
"1","(2275,2650)","0","pure_quanta_power","I113";
;
CDS_LIB"pure_quanta_power"
HDL_POWER"GND";
"A"1;
%"Q_RES"
"2","(1925,2900)","0","pure_quanta","I115";
;
LOCATION"PR427"
$SEC"1"
CDS_SEC"1"
WATTAGE"1/16W"
MATERIAL"CHIP"
TOLERANCE"1%"
VALUE"2.2"
PART_NUMBER"CS-2202FB00"
PACK_TYPE"0402LF"
CDS_LIB"pure_quanta";
"A"
$PN"1"47;
"B"
$PN"2"48;
%"Q_CAP"
"1","(1925,2350)","0","pure_quanta","I116";
;
LOCATION"PC138"
$SEC"1"
CDS_SEC"1"
MATERIAL"X6S"
TOLERANCE"10%"
VALUE"2.2UF"
PART_NUMBER"CH5222KEB01"
VOLTAGE"10V"
PACK_TYPE"C0402"
CDS_LIB"pure_quanta";
"B"
$PN"2"2;
"A"
$PN"1"48;
%"UNIVERSAL_GND"
"1","(1925,2150)","0","pure_quanta_power","I117";
;
CDS_LIB"pure_quanta_power"
HDL_POWER"GND";
"A"2;
%"UNIVERSAL_GND"
"1","(4050,1200)","0","pure_quanta_power","I120";
;
CDS_LIB"pure_quanta_power"
HDL_POWER"GND";
"A"56;
%"Q_RES"
"2","(1475,1425)","2","pure_quanta","I123";
;
LOCATION"PR426"
$SEC"1"
CDS_SEC"1"
WATTAGE"1/16W"
MATERIAL"EMPTY"
TOLERANCE"1%"
VALUE"8.87K"
PART_NUMBER"CS28872FB01"
PACK_TYPE"0402LF"
CDS_LIB"pure_quanta";
"A"
$PN"1"55;
"B"
$PN"2"3;
%"UNIVERSAL_GND"
"1","(1475,1200)","0","pure_quanta_power","I124";
;
CDS_LIB"pure_quanta_power"
HDL_POWER"GND";
"A"3;
%"Q_CAP"
"1","(975,1550)","0","pure_quanta","I125";
;
LOCATION"PC136_6"
$SEC"1"
CDS_SEC"1"
MATERIAL"X7R"
TOLERANCE"10%"
VALUE"0.1UF"
PART_NUMBER"CH4104K1B00"
VOLTAGE"25V"
PACK_TYPE"0402"
CDS_LIB"pure_quanta";
"B"
$PN"2"4;
"A"
$PN"1"46;
%"UNIVERSAL_GND"
"1","(975,1350)","0","pure_quanta_power","I126";
;
CDS_LIB"pure_quanta_power"
HDL_POWER"GND";
"A"4;
%"UNIVERSAL_GND"
"1","(4925,975)","0","pure_quanta_power","I127";
;
CDS_LIB"pure_quanta_power"
HDL_POWER"GND";
"A"5;
%"Q_RES"
"2","(4925,1200)","0","pure_quanta","I128";
;
LOCATION"PR518"
$SEC"1"
CDS_SEC"1"
PACK_TYPE"0402LF"
PART_NUMBER"CS-1504FB00"
MATERIAL"EMPTY"
WATTAGE"1/8W"
TOLERANCE"1%"
VALUE"1.5"
CDS_LIB"pure_quanta";
"A"
$PN"1"26;
"B"
$PN"2"5;
%"Q_CAP"
"1","(4925,1725)","0","pure_quanta","I129";
;
LOCATION"PC208"
$SEC"1"
CDS_SEC"1"
PART_NUMBER"CH1566K1B09"
PACK_TYPE"C0402"
VALUE"560PF"
VOLTAGE"50V"
TOLERANCE"10%"
MATERIAL"EMPTY"
CDS_LIB"pure_quanta";
"B"
$PN"2"26;
"A"
$PN"1"14;
%"UNIVERSAL_GND"
"1","(4850,3650)","0","pure_quanta_power","I130";
;
CDS_LIB"pure_quanta_power"
HDL_POWER"GND";
"A"6;
%"Q_RES"
"2","(4850,3875)","0","pure_quanta","I131";
;
LOCATION"PR517"
$SEC"1"
CDS_SEC"1"
WATTAGE"1/8W"
MATERIAL"EMPTY"
TOLERANCE"1%"
VALUE"1.5"
PART_NUMBER"CS-1504FB00"
PACK_TYPE"0402LF"
CDS_LIB"pure_quanta";
"A"
$PN"1"23;
"B"
$PN"2"6;
%"Q_CAP"
"1","(4850,4350)","0","pure_quanta","I132";
;
LOCATION"PC207"
$SEC"1"
CDS_SEC"1"
MATERIAL"EMPTY"
TOLERANCE"10%"
VALUE"560PF"
PART_NUMBER"CH1566K1B09"
VOLTAGE"50V"
PACK_TYPE"C0402"
CDS_LIB"pure_quanta";
"B"
$PN"2"23;
"A"
$PN"1"17;
%"VCC_CORE"
"1","(1875,5925)","0","pure_quanta_power","I133";
;
HDL_POWER"PVDDCR_CPU1_P1_PVCC"
CDS_LIB"pure_quanta_power";
"A"39;
%"VCC_CORE"
"1","(1925,3300)","0","pure_quanta_power","I134";
;
HDL_POWER"PVDDCR_CPU1_P1_PVCC"
CDS_LIB"pure_quanta_power";
"A"47;
%"UNIVERSAL_GND"
"1","(5575,1575)","0","pure_quanta_power","I135";
;
CDS_LIB"pure_quanta_power"
HDL_POWER"GND";
"A"7;
%"Q_INDUCTOR"
"1","(5775,1700)","2","pure_quanta","I136";
;
LOCATION"PL39"
$SEC"1"
CDS_SEC"1"
PART_NUMBER"CV+22Y0EZ00"
PACK_TYPE"SMLF"
MATERIAL"IND"
VALUE"0.22UH/33A"
NEEDS_NO_SIZE"TRUE"
CDS_LIB"pure_quanta";
"1"
$PN"1"53;
"2"
$PN"2"7;
%"UNIVERSAL_GND"
"1","(1425,3825)","0","pure_quanta_power","I20";
;
CDS_LIB"pure_quanta_power"
HDL_POWER"GND";
"A"8;
%"Q_RES"
"2","(1425,4050)","2","pure_quanta","I21";
;
LOCATION"PR270"
$SEC"1"
CDS_SEC"1"
WATTAGE"1/16W"
MATERIAL"EMPTY"
TOLERANCE"1%"
VALUE"8.87K"
PART_NUMBER"CS28872FB01"
PACK_TYPE"0402LF"
CDS_LIB"pure_quanta";
"A"
$PN"1"38;
"B"
$PN"2"8;
%"ISL99390FRZTR5935"
"1","(3350,4550)","0","pure_quanta","I31";
;
LOCATION"PU38"
$SEC"1"
CDS_SEC"1"
PART_TYPE"SMLF"
MATERIAL"IC"
VALUE"ISL99390FRZ-TR5935"
PART_NUMBER"AL099390004"
NEEDS_NO_SIZE"TRUE"
CDS_LMAN_SYM_OUTLINE"-300,700,250,-650"
CDS_LIB"pure_quanta";
"PGND2"
$PN"7_9-20_24"40;
"GL2"
$PN"41"32;
"GL1"
$PN"6"31;
"DNC"
$PN"31"34;
"EN"
$PN"35"37;
"PGND3"
$PN"40"40;
"VOS"
$PN"1"50;
"VIN2"
$PN"30"33;
"PGND1"
$PN"5"40;
"SW"
$PN"10_19"17;
"LSET"
$PN"37"38;
"IOUT"
$PN"38"35;
"TOUT_FLT"
$PN"36"42;
"PVCC"
$PN"4"39;
"PHASE"
$PN"32"16;
"VIN1"
$PN"25_29"33;
"BOOT"
$PN"33"30;
"AGND"
$PN"2"40;
"VCC"
$PN"3"37;
"REFIN"
$PN"39"36;
"PWM"
$PN"34"43;
%"UNIVERSAL_GND"
"1","(4000,3825)","0","pure_quanta_power","I36";
;
CDS_LIB"pure_quanta_power"
HDL_POWER"GND";
"A"40;
%"Q_CAP"
"1","(4625,5450)","0","pure_quanta","I39";
;
LOCATION"PC425_5"
$SEC"1"
CDS_SEC"1"
MATERIAL"X6S"
TOLERANCE"10%"
VALUE"1UF"
PART_NUMBER"CH5104KEB02"
VOLTAGE"25V"
PACK_TYPE"C0402"
CDS_LIB"pure_quanta";
"B"
$PN"2"22;
"A"
$PN"1"33;
%"Q_CAP"
"1","(5025,5450)","0","pure_quanta","I40";
;
LOCATION"PC426_5"
$SEC"1"
CDS_SEC"1"
MATERIAL"X6S"
TOLERANCE"10%"
VALUE"10UF"
PART_NUMBER"CH6104KEA00"
VOLTAGE"25V"
PACK_TYPE"C0805"
CDS_LIB"pure_quanta";
"B"
$PN"2"22;
"A"
$PN"1"33;
%"UNIVERSAL_GND"
"1","(5800,5100)","0","pure_quanta_power","I54";
;
CDS_LIB"pure_quanta_power"
HDL_POWER"GND";
"A"22;
%"Q_CAP"
"1","(5425,5450)","0","pure_quanta","I59";
;
LOCATION"PC427_5"
$SEC"1"
CDS_SEC"1"
MATERIAL"X6S"
TOLERANCE"10%"
VALUE"10UF"
PART_NUMBER"CH6104KEA00"
VOLTAGE"25V"
PACK_TYPE"C0805"
CDS_LIB"pure_quanta";
"B"
$PN"2"22;
"A"
$PN"1"33;
%"Q_CAP"
"1","(5800,5450)","0","pure_quanta","I60";
;
LOCATION"PC429_5"
$SEC"1"
CDS_SEC"1"
MATERIAL"X6S"
TOLERANCE"10%"
VALUE"10UF"
PART_NUMBER"CH6104KEA00"
VOLTAGE"25V"
PACK_TYPE"C0805"
CDS_LIB"pure_quanta";
"B"
$PN"2"22;
"A"
$PN"1"33;
%"VCC_CORE"
"1","(5800,5800)","0","pure_quanta_power","I61";
;
HDL_POWER"SW_P12V_STBY_PVDDCR_CPU1_P1_FLT"
CDS_LIB"pure_quanta_power";
"A"33;
%"Q_RES"
"1","(5775,3500)","0","pure_quanta","I76";
;
LOCATION"PR273"
$SEC"1"
CDS_SEC"1"
WATTAGE"1/16W"
MATERIAL"CHIP"
TOLERANCE"5%"
VALUE"0"
PART_NUMBER"CS00002JB38"
PACK_TYPE"0402LF"
CDS_LIB"pure_quanta";
"B"
$PN"2"52;
"A"
$PN"1"50;
%"VCC_CORE"
"1","(8725,4700)","0","pure_quanta_power","I77";
;
HDL_POWER"PVDDCR_CPU1_P1"
CDS_LIB"pure_quanta_power";
"A"52;
%"UNIVERSAL_GND"
"1","(8725,4000)","0","pure_quanta_power","I78";
;
CDS_LIB"pure_quanta_power"
HDL_POWER"GND";
"A"18;
%"Q_CAP"
"1","(8725,4350)","0","pure_quanta","I79";
;
LOCATION"PC431_5"
$SEC"1"
CDS_SEC"1"
MATERIAL"X6S"
TOLERANCE"20%"
VALUE"22UF"
PART_NUMBER"TMP_QCH622KMEA01"
VOLTAGE"4V"
PACK_TYPE"0805"
CDS_LIB"pure_quanta";
"B"
$PN"2"18;
"A"
$PN"1"52;
%"Q_CAP"
"1","(8300,4350)","0","pure_quanta","I80";
;
LOCATION"PC430_5"
$SEC"1"
CDS_SEC"1"
MATERIAL"X6S"
TOLERANCE"20%"
VALUE"22UF"
PART_NUMBER"TMP_QCH622KMEA01"
VOLTAGE"4V"
PACK_TYPE"0805"
CDS_LIB"pure_quanta";
"B"
$PN"2"18;
"A"
$PN"1"52;
%"Q_INDUCTOR4P_14"
"1","(6800,4425)","0","pure_quanta","I82";
;
LOCATION"PL45"
$SEC"1"
CDS_SEC"1"
PART_TYPE"SMLF"
MATERIAL"IND"
VALUE"150NH"
PART_NUMBER"CV+15^0TZ04"
NEEDS_NO_SIZE"TRUE"
CDS_LIB"pure_quanta";
"1"
$PN"1"17;
"4"
$PN"4"52;
"3"
$PN"3"51;
"2"
$PN"2"20;
%"Q_CAP"
"1","(925,4175)","0","pure_quanta","I83";
;
LOCATION"PC422_5"
$SEC"1"
CDS_SEC"1"
MATERIAL"X7R"
TOLERANCE"10%"
VALUE"0.1UF"
PART_NUMBER"CH4104K1B00"
VOLTAGE"25V"
PACK_TYPE"0402"
CDS_LIB"pure_quanta";
"B"
$PN"2"11;
"A"
$PN"1"36;
%"Q_CAP"
"1","(5600,4775)","0","pure_quanta","I84";
;
LOCATION"PC428"
$SEC"1"
CDS_SEC"1"
MATERIAL"X7R"
TOLERANCE"10%"
VALUE"0.22UF"
PART_NUMBER"CH4223K1B00"
VOLTAGE"16V"
PACK_TYPE"0402"
CDS_LIB"pure_quanta";
"B"
$PN"2"16;
"A"
$PN"1"21;
%"Q_RES"
"1","(4700,4900)","0","pure_quanta","I85";
;
LOCATION"PR272"
$SEC"1"
CDS_SEC"1"
PACK_TYPE"0402LF"
TOLERANCE"1%"
MATERIAL"CHIP"
WATTAGE"1/16W"
VALUE"4.7"
PART_NUMBER"CS-4702FB19"
CDS_LIB"pure_quanta";
"B"
$PN"2"21;
"A"
$PN"1"30;
%"Q_CAP"
"1","(4200,5450)","0","pure_quanta","I86";
;
LOCATION"PC424_5"
$SEC"1"
CDS_SEC"1"
MATERIAL"X7R"
TOLERANCE"10%"
VALUE"0.1UF"
PART_NUMBER"CH4104K1B00"
VOLTAGE"25V"
PACK_TYPE"0402"
CDS_LIB"pure_quanta";
"B"
$PN"2"22;
"A"
$PN"1"33;
%"Q_CAP"
"1","(1875,4975)","0","pure_quanta","I87";
;
LOCATION"PC421"
$SEC"1"
CDS_SEC"1"
MATERIAL"X6S"
TOLERANCE"10%"
VALUE"2.2UF"
PART_NUMBER"CH5222KEB01"
VOLTAGE"10V"
PACK_TYPE"C0402"
CDS_LIB"pure_quanta";
"B"
$PN"2"9;
"A"
$PN"1"37;
%"UNIVERSAL_GND"
"1","(1875,4775)","0","pure_quanta_power","I88";
;
CDS_LIB"pure_quanta_power"
HDL_POWER"GND";
"A"9;
%"UNIVERSAL_GND"
"1","(2225,5275)","0","pure_quanta_power","I89";
;
CDS_LIB"pure_quanta_power"
HDL_POWER"GND";
"A"10;
%"Q_RES"
"2","(1875,5525)","0","pure_quanta","I90";
;
LOCATION"PR271"
$SEC"1"
CDS_SEC"1"
WATTAGE"1/16W"
MATERIAL"CHIP"
TOLERANCE"1%"
VALUE"2.2"
PART_NUMBER"CS-2202FB00"
PACK_TYPE"0402LF"
CDS_LIB"pure_quanta";
"A"
$PN"1"39;
"B"
$PN"2"37;
%"Q_CAP"
"1","(2225,5550)","0","pure_quanta","I91";
;
LOCATION"PC423_C1P1_5"
$SEC"1"
CDS_SEC"1"
MATERIAL"X6S"
TOLERANCE"10%"
VALUE"2.2UF"
PART_NUMBER"CH5222KEB01"
VOLTAGE"10V"
PACK_TYPE"C0402"
CDS_LIB"pure_quanta";
"B"
$PN"2"10;
"A"
$PN"1"39;
%"UNIVERSAL_GND"
"1","(925,3975)","0","pure_quanta_power","I93";
;
CDS_LIB"pure_quanta_power"
HDL_POWER"GND";
"A"11;
%"ISL99390FRZTR5935"
"1","(3400,1925)","0","pure_quanta","I94";
;
LOCATION"PU33"
$SEC"1"
CDS_SEC"1"
PART_TYPE"SMLF"
MATERIAL"IC"
VALUE"ISL99390FRZ-TR5935"
PART_NUMBER"AL099390004"
NEEDS_NO_SIZE"TRUE"
CDS_LMAN_SYM_OUTLINE"-300,700,250,-650"
CDS_LIB"pure_quanta";
"PGND2"
$PN"7_9-20_24"56;
"GL2"
$PN"41"28;
"GL1"
$PN"6"27;
"DNC"
$PN"31"41;
"EN"
$PN"35"48;
"PGND3"
$PN"40"56;
"VOS"
$PN"1"54;
"VIN2"
$PN"30"49;
"PGND1"
$PN"5"56;
"SW"
$PN"10_19"14;
"LSET"
$PN"37"55;
"IOUT"
$PN"38"45;
"TOUT_FLT"
$PN"36"44;
"PVCC"
$PN"4"47;
"PHASE"
$PN"32"15;
"VIN1"
$PN"25_29"49;
"BOOT"
$PN"33"29;
"AGND"
$PN"2"56;
"VCC"
$PN"3"48;
"REFIN"
$PN"39"46;
"PWM"
$PN"34"57;
%"VCC_CORE"
"1","(8775,2075)","0","pure_quanta_power","I95";
;
HDL_POWER"PVDDCR_CPU1_P1"
CDS_LIB"pure_quanta_power";
"A"25;
%"Q_CAP"
"1","(8775,1725)","0","pure_quanta","I96";
;
LOCATION"PC149_6"
$SEC"1"
CDS_SEC"1"
MATERIAL"X6S"
TOLERANCE"20%"
VALUE"22UF"
PART_NUMBER"TMP_QCH622KMEA01"
VOLTAGE"4V"
PACK_TYPE"0805"
CDS_LIB"pure_quanta";
"B"
$PN"2"19;
"A"
$PN"1"25;
%"Q_CAP"
"1","(8350,1725)","0","pure_quanta","I97";
;
LOCATION"PC148_6"
$SEC"1"
CDS_SEC"1"
MATERIAL"X6S"
TOLERANCE"20%"
VALUE"22UF"
PART_NUMBER"TMP_QCH622KMEA01"
VOLTAGE"4V"
PACK_TYPE"0805"
CDS_LIB"pure_quanta";
"B"
$PN"2"19;
"A"
$PN"1"25;
%"UNIVERSAL_GND"
"1","(8775,1375)","0","pure_quanta_power","I98";
;
CDS_LIB"pure_quanta_power"
HDL_POWER"GND";
"A"19;
END.
